# T6G (Grand Teton) — schematic netlist excerpt (pin names and nets, part order shuffled) for the footprints in the layout excerpt that follows; sources: Cadence DE-HDL packaged netlist, KiCad conversion of 04192023_DAF0TMB3IC0_F0TG_MB_C_brd_V02_OCP.brd

R754  Q_RES  10K 5% EMPTY  pkg 0402LF  page 76 : A = GND ; B = SPI_CPU1_CLK
R55  Q_RES  33.2 1% CHIP  pkg 0402LF  page 250 : A = SMB_PCIE0_3V3AUX_SDA ; B = SMB_PCIE0_3V3AUX_SDA_R

(kicad_pcb
	(version 20260206)
	(generator "pcbnew")
	(generator_version "10.0")
	(general
		(thickness 1.6)
		(legacy_teardrops no)
	)
	(paper "A4")
	(title_block
		(title "04192023_DAF0TMB3IC0_F0TG_MB_C_brd_V02_OCP.brd")
		(comment 1 "Grand Teton / footprints 5178-5179 of 8354")
	)
	(layers
		(0 "F.Cu" signal "TOP")
		(4 "In1.Cu" signal "GND")
		(6 "In2.Cu" signal "IN1")
		(8 "In3.Cu" signal "GND1")
		(10 "In4.Cu" signal "IN2")
		(12 "In5.Cu" signal "GND2")
		(14 "In6.Cu" signal "IN3")
		(16 "In7.Cu" signal "GND3")
		(18 "In8.Cu" signal "VCC")
		(20 "In9.Cu" signal "VCC1")
		(22 "In10.Cu" signal "GND4")
		(24 "In11.Cu" signal "IN4")
		(26 "In12.Cu" signal "GND5")
		(28 "In13.Cu" signal "IN5")
		(30 "In14.Cu" signal "GND6")
		(32 "In15.Cu" signal "IN6")
		(34 "In16.Cu" signal "GND7")
		(2 "B.Cu" signal "BOTTOM")
		(9 "F.Adhes" user "F.Adhesive")
		(11 "B.Adhes" user "B.Adhesive")
		(13 "F.Paste" user "Package Geometry/Pastemask Top")
		(15 "B.Paste" user "Package Geometry/Pastemask Bottom")
		(5 "F.SilkS" user "Ref Des/Silkscreen Top")
		(7 "B.SilkS" user "Ref Des/Silkscreen Bottom")
		(1 "F.Mask" user "Board Geometry/Soldermask Top")
		(3 "B.Mask" user "Board Geometry/Soldermask Bottom")
		(17 "Dwgs.User" user "User.Drawings")
		(19 "Cmts.User" user "User.Comments")
		(21 "Eco1.User" user "User.Eco1")
		(23 "Eco2.User" user "User.Eco2")
		(25 "Edge.Cuts" user "Board Geometry/Outline")
		(27 "Margin" user)
		(31 "F.CrtYd" user "Package Geometry/Place Bound Top")
		(29 "B.CrtYd" user "Package Geometry/Place Bound Bottom")
		(35 "F.Fab" user "Ref Des/Assembly Top")
		(33 "B.Fab" user "Ref Des/Assembly Bottom")
	)
	(footprint ""
		(layer "B.Cu")
		(at 164.508688 -9.013444 90)
		(property "Reference" "R55"
			(at 0 0 90)
			(layer "B.SilkS")
			(hide yes)
			(effects
				(font
					(size 1.27 1.27)
				)
				(justify mirror)
			)
		)
		(property "Value" ""
			(at 0 0 90)
			(layer "B.Fab")
			(effects
				(font
					(size 1.27 1.27)
				)
				(justify mirror)
			)
		)
		(duplicate_pad_numbers_are_jumpers no)
		(fp_line
			(start 0.7874 -0.4064)
			(end -0.7874 -0.4064)
			(stroke
				(width 0.1524)
				(type default)
			)
			(layer "B.SilkS")
		)
		(fp_line
			(start -0.7874 -0.4064)
			(end -0.7874 0.4064)
			(stroke
				(width 0.1524)
				(type default)
			)
			(layer "B.SilkS")
		)
		(fp_line
			(start 0.7874 0.4064)
			(end 0.7874 -0.4064)
			(stroke
				(width 0.1524)
				(type default)
			)
			(layer "B.SilkS")
		)
		(fp_line
			(start -0.7874 0.4064)
			(end 0.7874 0.4064)
			(stroke
				(width 0.1524)
				(type default)
			)
			(layer "B.SilkS")
		)
		(fp_line
			(start 0.67945 -0.305054)
			(end 0.12065 -0.305054)
			(stroke
				(width 0.1)
				(type default)
			)
			(layer "B.Fab")
		)
		(fp_line
			(start 0.12065 -0.305054)
			(end 0.12065 -0.2794)
			(stroke
				(width 0.1)
				(type default)
			)
			(layer "B.Fab")
		)
		(fp_line
			(start -0.12065 -0.3048)
			(end -0.67945 -0.3048)
			(stroke
				(width 0.1)
				(type default)
			)
			(layer "B.Fab")
		)
		(fp_line
			(start -0.67945 -0.3048)
			(end -0.67945 0.3048)
			(stroke
				(width 0.1)
				(type default)
			)
			(layer "B.Fab")
		)
		(fp_line
			(start 0.12065 -0.2794)
			(end -0.12065 -0.2794)
			(stroke
				(width 0.1)
				(type default)
			)
			(layer "B.Fab")
		)
		(fp_line
			(start -0.12065 -0.2794)
			(end -0.12065 -0.3048)
			(stroke
				(width 0.1)
				(type default)
			)
			(layer "B.Fab")
		)
		(fp_line
			(start 0.12065 0.2794)
			(end 0.12065 0.3048)
			(stroke
				(width 0.1)
				(type default)
			)
			(layer "B.Fab")
		)
		(fp_line
			(start -0.120396 0.2794)
			(end 0.12065 0.2794)
			(stroke
				(width 0.1)
				(type default)
			)
			(layer "B.Fab")
		)
		(fp_line
			(start 0.67945 0.3048)
			(end 0.67945 -0.305054)
			(stroke
				(width 0.1)
				(type default)
			)
			(layer "B.Fab")
		)
		(fp_line
			(start 0.12065 0.3048)
			(end 0.67945 0.3048)
			(stroke
				(width 0.1)
				(type default)
			)
			(layer "B.Fab")
		)
		(fp_line
			(start -0.120396 0.3048)
			(end -0.120396 0.2794)
			(stroke
				(width 0.1)
				(type default)
			)
			(layer "B.Fab")
		)
		(fp_line
			(start -0.67945 0.3048)
			(end -0.120396 0.3048)
			(stroke
				(width 0.1)
				(type default)
			)
			(layer "B.Fab")
		)
		(pad "1" smd circle
			(at 0.40005 0 270)
			(size 0 0)
			(layers "B.Cu" "B.Mask" "B.Paste")
			(net "SMB_PCIE0_3V3AUX_SDA")
		)
		(pad "2" smd circle
			(at -0.40005 0 270)
			(size 0 0)
			(layers "B.Cu" "B.Mask" "B.Paste")
			(net "SMB_PCIE0_3V3AUX_SDA_R")
		)
	)
	(footprint ""
		(layer "B.Cu")
		(at 153.865834 -322.903342 -90)
		(property "Reference" "R754"
			(at 0 0 90)
			(layer "B.SilkS")
			(hide yes)
			(effects
				(font
					(size 1.27 1.27)
				)
				(justify mirror)
			)
		)
		(property "Value" ""
			(at 0 0 90)
			(layer "B.Fab")
			(effects
				(font
					(size 1.27 1.27)
				)
				(justify mirror)
			)
		)
		(duplicate_pad_numbers_are_jumpers no)
		(fp_line
			(start -0.7874 0.4064)
			(end 0.7874 0.4064)
			(stroke
				(width 0.1524)
				(type default)
			)
			(layer "B.SilkS")
		)
		(fp_line
			(start 0.7874 0.4064)
			(end 0.7874 -0.4064)
			(stroke
				(width 0.1524)
				(type default)
			)
			(layer "B.SilkS")
		)
		(fp_line
			(start -0.7874 -0.4064)
			(end -0.7874 0.4064)
			(stroke
				(width 0.1524)
				(type default)
			)
			(layer "B.SilkS")
		)
		(fp_line
			(start 0.7874 -0.4064)
			(end -0.7874 -0.4064)
			(stroke
				(width 0.1524)
				(type default)
			)
			(layer "B.SilkS")
		)
		(fp_line
			(start -0.67945 0.3048)
			(end -0.120396 0.3048)
			(stroke
				(width 0.1)
				(type default)
			)
			(layer "B.Fab")
		)
		(fp_line
			(start -0.120396 0.3048)
			(end -0.120396 0.2794)
			(stroke
				(width 0.1)
				(type default)
			)
			(layer "B.Fab")
		)
		(fp_line
			(start 0.12065 0.3048)
			(end 0.67945 0.3048)
			(stroke
				(width 0.1)
				(type default)
			)
			(layer "B.Fab")
		)
		(fp_line
			(start 0.67945 0.3048)
			(end 0.67945 -0.305054)
			(stroke
				(width 0.1)
				(type default)
			)
			(layer "B.Fab")
		)
		(fp_line
			(start -0.120396 0.2794)
			(end 0.12065 0.2794)
			(stroke
				(width 0.1)
				(type default)
			)
			(layer "B.Fab")
		)
		(fp_line
			(start 0.12065 0.2794)
			(end 0.12065 0.3048)
			(stroke
				(width 0.1)
				(type default)
			)
			(layer "B.Fab")
		)
		(fp_line
			(start -0.12065 -0.2794)
			(end -0.12065 -0.3048)
			(stroke
				(width 0.1)
				(type default)
			)
			(layer "B.Fab")
		)
		(fp_line
			(start 0.12065 -0.2794)
			(end -0.12065 -0.2794)
			(stroke
				(width 0.1)
				(type default)
			)
			(layer "B.Fab")
		)
		(fp_line
			(start -0.67945 -0.3048)
			(end -0.67945 0.3048)
			(stroke
				(width 0.1)
				(type default)
			)
			(layer "B.Fab")
		)
		(fp_line
			(start -0.12065 -0.3048)
			(end -0.67945 -0.3048)
			(stroke
				(width 0.1)
				(type default)
			)
			(layer "B.Fab")
		)
		(fp_line
			(start 0.12065 -0.305054)
			(end 0.12065 -0.2794)
			(stroke
				(width 0.1)
				(type default)
			)
			(layer "B.Fab")
		)
		(fp_line
			(start 0.67945 -0.305054)
			(end 0.12065 -0.305054)
			(stroke
				(width 0.1)
				(type default)
			)
			(layer "B.Fab")
		)
		(pad "1" smd circle
			(at 0.40005 0 90)
			(size 0 0)
			(layers "B.Cu" "B.Mask" "B.Paste")
			(net "GND")
		)
		(pad "2" smd circle
			(at -0.40005 0 90)
			(size 0 0)
			(layers "B.Cu" "B.Mask" "B.Paste")
			(net "SPI_CPU1_CLK")
		)
	)
)
